FILE_TYPE=LIBRARY_PARTS;
primitive '74LVC1G07GV';
  pin
    'VCC':
      PIN_NUMBER='(5)';
      PINUSE='POWER';
      NO_LOAD_CHECK='Both';
      NO_IO_CHECK='Both';
      NO_ASSERT_CHECK='TRUE';
      NO_DIR_CHECK='TRUE';
      ALLOW_CONNECT='TRUE';
    'A':
      PIN_NUMBER='(2)';
      INPUT_LOAD='(-0.01,0.01)';
    'GND':
      PIN_NUMBER='(3)';
      PINUSE='POWER';
      NO_LOAD_CHECK='Both';
      NO_IO_CHECK='Both';
      NO_ASSERT_CHECK='TRUE';
      NO_DIR_CHECK='TRUE';
      ALLOW_CONNECT='TRUE';
    'Y':
      PIN_NUMBER='(4)';
      OUTPUT_TYPE='(OC,AND)';
      OUTPUT_LOAD='(1.0,*)';
    'NC1':
      PIN_NUMBER='(1)';
      OUTPUT_TYPE='(TS,TS)';
      INPUT_LOAD='(-0.01,0.01)';
      OUTPUT_LOAD='(1.0,-1.0)';
  end_pin;
  body
    PART_NAME='74LVC1G07GV';
    BODY_NAME='74LVC1G07GV';
    PHYS_DES_PREFIX='U';
    CLASS='IC';
  end_body;
end_primitive;

END.
